(kicad_pcb
	(version 20241229)
	(generator "pcbnew")
	(generator_version "9.0")
	(general
		(thickness 1.62)
		(legacy_teardrops no)
	)
	(paper "A3")
	(title_block
		(title "COM Express 7 Baseboard")
		(date "2025-02-04")
		(rev "1.1.2")
		(company "Antmicro Ltd")
		(comment 1 "www.antmicro.com")
		(comment 9 "footprint 546 of 802 (J5), pads 1-42 of 71")
	)
	(layers
		(0 "F.Cu" signal)
		(4 "In1.Cu" signal)
		(6 "In2.Cu" signal)
		(8 "In3.Cu" signal)
		(10 "In4.Cu" signal)
		(12 "In5.Cu" signal)
		(14 "In6.Cu" signal)
		(2 "B.Cu" signal)
		(9 "F.Adhes" user "F.Adhesive")
		(11 "B.Adhes" user "B.Adhesive")
		(13 "F.Paste" user)
		(15 "B.Paste" user)
		(5 "F.SilkS" user "F.Silkscreen")
		(7 "B.SilkS" user "B.Silkscreen")
		(1 "F.Mask" user)
		(3 "B.Mask" user)
		(17 "Dwgs.User" user "User.Drawings")
		(19 "Cmts.User" user "User.Comments")
		(21 "Eco1.User" user "User.Eco1")
		(23 "Eco2.User" user "User.Eco2")
		(25 "Edge.Cuts" user)
		(27 "Margin" user)
		(31 "F.CrtYd" user "F.Courtyard")
		(29 "B.CrtYd" user "B.Courtyard")
		(35 "F.Fab" user)
		(33 "B.Fab" user)
	)
	(footprint "antmicro-footprints:Bus_M.2_Socket_Key_M_Amphenol_MDT180M03001"
		(layer "B.Cu")
		(at 180.15 102.11 -90)
		(property "Reference" "J5"
			(at -12.26 5 90)
			(layer "B.SilkS")
			(effects
				(font
					(size 0.7 0.7)
					(thickness 0.15)
				)
				(justify left bottom mirror)
			)
		)
		(property "Value" "Bus_M.2_MDT180M03001"
			(at 0 -6.3 90)
			(layer "B.Fab")
			(hide yes)
			(effects
				(font
					(size 0.7 0.7)
					(thickness 0.15)
				)
				(justify left bottom mirror)
			)
		)
		(property "Datasheet" "https://cdn.amphenol-cs.com/media/wysiwyg/files/drawing/mdt180xxx001.pdf"
			(at 0 0 90)
			(layer "B.Fab")
			(hide yes)
			(effects
				(font
					(size 1.27 1.27)
					(thickness 0.15)
				)
				(justify mirror)
			)
		)
		(property "Manufacturer" "Amphenol"
			(at 0 0 270)
			(unlocked yes)
			(layer "B.Fab")
			(hide yes)
			(effects
				(font
					(size 1 1)
					(thickness 0.15)
				)
				(justify mirror)
			)
		)
		(property "MPN" "MDT180M03001"
			(at 0 0 270)
			(unlocked yes)
			(layer "B.Fab")
			(hide yes)
			(effects
				(font
					(size 1 1)
					(thickness 0.15)
				)
				(justify mirror)
			)
		)
		(property "Author" "Antmicro"
			(at 0 0 270)
			(unlocked yes)
			(layer "B.Fab")
			(hide yes)
			(effects
				(font
					(size 1 1)
					(thickness 0.15)
				)
				(justify mirror)
			)
		)
		(property "License" "Apache-2.0"
			(at 0 0 270)
			(unlocked yes)
			(layer "B.Fab")
			(hide yes)
			(effects
				(font
					(size 1 1)
					(thickness 0.15)
				)
				(justify mirror)
			)
		)
		(sheetname "M.2 key M #1")
		(sheetfile "m2keym_low.kicad_sch")
		(attr smd)
		(pad "" np_thru_hole circle
			(at -11 2.4 270)
			(size 1.15 1.15)
			(drill 1.15)
			(layers "*.Cu" "*.Mask")
		)
		(pad "" np_thru_hole circle
			(at 11 2.4 270)
			(size 1.65 1.65)
			(drill 1.65)
			(layers "*.Cu" "*.Mask")
		)
		(pad "1" smd rect
			(at -9.25 3.95 270)
			(size 0.3 1.5)
			(layers "B.Cu" "B.Mask" "B.Paste")
			(net 1 "GND")
			(pinfunction "GND")
			(pintype "power_in")
			(teardrops
				(best_length_ratio 0.2)
				(max_length 1)
				(best_width_ratio 0.9)
				(max_width 2)
				(curved_edges yes)
				(filter_ratio 0.9)
				(enabled yes)
				(allow_two_segments yes)
				(prefer_zone_connections yes)
			)
		)
		(pad "2" smd rect
			(at -9 1.31 270)
			(size 0.3 1.5)
			(layers "B.Cu" "B.Mask" "B.Paste")
			(net 969 "/M.2 key M #1/M2_3V3")
			(pinfunction "3V3")
			(pintype "passive")
			(teardrops
				(best_length_ratio 0.2)
				(max_length 1)
				(best_width_ratio 0.9)
				(max_width 2)
				(curved_edges yes)
				(filter_ratio 0.9)
				(enabled yes)
				(allow_two_segments yes)
				(prefer_zone_connections yes)
			)
		)
		(pad "3" smd rect
			(at -8.75 3.95 270)
			(size 0.3 1.5)
			(layers "B.Cu" "B.Mask" "B.Paste")
			(net 1 "GND")
			(pinfunction "GND")
			(pintype "passive")
			(teardrops
				(best_length_ratio 0.2)
				(max_length 1)
				(best_width_ratio 0.9)
				(max_width 2)
				(curved_edges yes)
				(filter_ratio 0.9)
				(enabled yes)
				(allow_two_segments yes)
				(prefer_zone_connections yes)
			)
		)
		(pad "4" smd rect
			(at -8.5 1.31 270)
			(size 0.3 1.5)
			(layers "B.Cu" "B.Mask" "B.Paste")
			(net 969 "/M.2 key M #1/M2_3V3")
			(pinfunction "3V3")
			(pintype "passive")
			(teardrops
				(best_length_ratio 0.2)
				(max_length 1)
				(best_width_ratio 0.9)
				(max_width 2)
				(curved_edges yes)
				(filter_ratio 0.9)
				(enabled yes)
				(allow_two_segments yes)
				(prefer_zone_connections yes)
			)
		)
		(pad "5" smd rect
			(at -8.25 3.95 270)
			(size 0.3 1.5)
			(layers "B.Cu" "B.Mask" "B.Paste")
			(net 239 "/Com Express 7 Interfaces/PCIe_{B2Bx4}.RX3+")
			(pinfunction "PER3_N")
			(pintype "output")
			(teardrops
				(best_length_ratio 0.2)
				(max_length 1)
				(best_width_ratio 0.9)
				(max_width 2)
				(curved_edges yes)
				(filter_ratio 0.9)
				(enabled yes)
				(allow_two_segments yes)
				(prefer_zone_connections yes)
			)
		)
		(pad "6" smd rect
			(at -8 1.31 270)
			(size 0.3 1.5)
			(layers "B.Cu" "B.Mask" "B.Paste")
			(net 223 "unconnected-(J5-NC-Pad6)")
			(pinfunction "NC")
			(pintype "no_connect")
			(teardrops
				(best_length_ratio 0.2)
				(max_length 1)
				(best_width_ratio 0.9)
				(max_width 2)
				(curved_edges yes)
				(filter_ratio 0.9)
				(enabled yes)
				(allow_two_segments yes)
				(prefer_zone_connections yes)
			)
		)
		(pad "7" smd rect
			(at -7.75 3.95 270)
			(size 0.3 1.5)
			(layers "B.Cu" "B.Mask" "B.Paste")
			(net 237 "/Com Express 7 Interfaces/PCIe_{B2Bx4}.RX3-")
			(pinfunction "PER3_P")
			(pintype "output")
			(teardrops
				(best_length_ratio 0.2)
				(max_length 1)
				(best_width_ratio 0.9)
				(max_width 2)
				(curved_edges yes)
				(filter_ratio 0.9)
				(enabled yes)
				(allow_two_segments yes)
				(prefer_zone_connections yes)
			)
		)
		(pad "8" smd rect
			(at -7.5 1.31 270)
			(size 0.3 1.5)
			(layers "B.Cu" "B.Mask" "B.Paste")
			(net 224 "unconnected-(J5-NC-Pad8)")
			(pinfunction "NC")
			(pintype "no_connect")
			(teardrops
				(best_length_ratio 0.2)
				(max_length 1)
				(best_width_ratio 0.9)
				(max_width 2)
				(curved_edges yes)
				(filter_ratio 0.9)
				(enabled yes)
				(allow_two_segments yes)
				(prefer_zone_connections yes)
			)
		)
		(pad "9" smd rect
			(at -7.25 3.95 270)
			(size 0.3 1.5)
			(layers "B.Cu" "B.Mask" "B.Paste")
			(net 1 "GND")
			(pinfunction "GND")
			(pintype "passive")
			(teardrops
				(best_length_ratio 0.2)
				(max_length 1)
				(best_width_ratio 0.9)
				(max_width 2)
				(curved_edges yes)
				(filter_ratio 0.9)
				(enabled yes)
				(allow_two_segments yes)
				(prefer_zone_connections yes)
			)
		)
		(pad "10" smd rect
			(at -7 1.31 270)
			(size 0.3 1.5)
			(layers "B.Cu" "B.Mask" "B.Paste")
			(net 935 "Net-(D13-C)")
			(pinfunction "LED")
			(pintype "passive")
			(teardrops
				(best_length_ratio 0.2)
				(max_length 1)
				(best_width_ratio 0.9)
				(max_width 2)
				(curved_edges yes)
				(filter_ratio 0.9)
				(enabled yes)
				(allow_two_segments yes)
				(prefer_zone_connections yes)
			)
		)
		(pad "11" smd rect
			(at -6.75 3.95 270)
			(size 0.3 1.5)
			(layers "B.Cu" "B.Mask" "B.Paste")
			(net 242 "/Com Express 7 Interfaces/PCIe_{B2Bx4}.TX3+")
			(pinfunction "PET3_N")
			(pintype "input")
			(teardrops
				(best_length_ratio 0.2)
				(max_length 1)
				(best_width_ratio 0.9)
				(max_width 2)
				(curved_edges yes)
				(filter_ratio 0.9)
				(enabled yes)
				(allow_two_segments yes)
				(prefer_zone_connections yes)
			)
		)
		(pad "12" smd rect
			(at -6.5 1.31 270)
			(size 0.3 1.5)
			(layers "B.Cu" "B.Mask" "B.Paste")
			(net 969 "/M.2 key M #1/M2_3V3")
			(pinfunction "3V3")
			(pintype "passive")
			(teardrops
				(best_length_ratio 0.2)
				(max_length 1)
				(best_width_ratio 0.9)
				(max_width 2)
				(curved_edges yes)
				(filter_ratio 0.9)
				(enabled yes)
				(allow_two_segments yes)
				(prefer_zone_connections yes)
			)
		)
		(pad "13" smd rect
			(at -6.25 3.95 270)
			(size 0.3 1.5)
			(layers "B.Cu" "B.Mask" "B.Paste")
			(net 241 "/Com Express 7 Interfaces/PCIe_{B2Bx4}.TX3-")
			(pinfunction "PET3_P")
			(pintype "input")
			(teardrops
				(best_length_ratio 0.2)
				(max_length 1)
				(best_width_ratio 0.9)
				(max_width 2)
				(curved_edges yes)
				(filter_ratio 0.9)
				(enabled yes)
				(allow_two_segments yes)
				(prefer_zone_connections yes)
			)
		)
		(pad "14" smd rect
			(at -6 1.31 270)
			(size 0.3 1.5)
			(layers "B.Cu" "B.Mask" "B.Paste")
			(net 969 "/M.2 key M #1/M2_3V3")
			(pinfunction "3V3")
			(pintype "passive")
			(teardrops
				(best_length_ratio 0.2)
				(max_length 1)
				(best_width_ratio 0.9)
				(max_width 2)
				(curved_edges yes)
				(filter_ratio 0.9)
				(enabled yes)
				(allow_two_segments yes)
				(prefer_zone_connections yes)
			)
		)
		(pad "15" smd rect
			(at -5.75 3.95 270)
			(size 0.3 1.5)
			(layers "B.Cu" "B.Mask" "B.Paste")
			(net 1 "GND")
			(pinfunction "GND")
			(pintype "passive")
			(teardrops
				(best_length_ratio 0.2)
				(max_length 1)
				(best_width_ratio 0.9)
				(max_width 2)
				(curved_edges yes)
				(filter_ratio 0.9)
				(enabled yes)
				(allow_two_segments yes)
				(prefer_zone_connections yes)
			)
		)
		(pad "16" smd rect
			(at -5.5 1.31 270)
			(size 0.3 1.5)
			(layers "B.Cu" "B.Mask" "B.Paste")
			(net 969 "/M.2 key M #1/M2_3V3")
			(pinfunction "3V3")
			(pintype "passive")
			(teardrops
				(best_length_ratio 0.2)
				(max_length 1)
				(best_width_ratio 0.9)
				(max_width 2)
				(curved_edges yes)
				(filter_ratio 0.9)
				(enabled yes)
				(allow_two_segments yes)
				(prefer_zone_connections yes)
			)
		)
		(pad "17" smd rect
			(at -5.25 3.95 270)
			(size 0.3 1.5)
			(layers "B.Cu" "B.Mask" "B.Paste")
			(net 244 "/Com Express 7 Interfaces/PCIe_{B2Bx4}.RX2+")
			(pinfunction "PER2_N")
			(pintype "output")
			(teardrops
				(best_length_ratio 0.2)
				(max_length 1)
				(best_width_ratio 0.9)
				(max_width 2)
				(curved_edges yes)
				(filter_ratio 0.9)
				(enabled yes)
				(allow_two_segments yes)
				(prefer_zone_connections yes)
			)
		)
		(pad "18" smd rect
			(at -5 1.31 270)
			(size 0.3 1.5)
			(layers "B.Cu" "B.Mask" "B.Paste")
			(net 969 "/M.2 key M #1/M2_3V3")
			(pinfunction "3V3")
			(pintype "passive")
			(teardrops
				(best_length_ratio 0.2)
				(max_length 1)
				(best_width_ratio 0.9)
				(max_width 2)
				(curved_edges yes)
				(filter_ratio 0.9)
				(enabled yes)
				(allow_two_segments yes)
				(prefer_zone_connections yes)
			)
		)
		(pad "19" smd rect
			(at -4.75 3.95 270)
			(size 0.3 1.5)
			(layers "B.Cu" "B.Mask" "B.Paste")
			(net 243 "/Com Express 7 Interfaces/PCIe_{B2Bx4}.RX2-")
			(pinfunction "PER2_P")
			(pintype "output")
			(teardrops
				(best_length_ratio 0.2)
				(max_length 1)
				(best_width_ratio 0.9)
				(max_width 2)
				(curved_edges yes)
				(filter_ratio 0.9)
				(enabled yes)
				(allow_two_segments yes)
				(prefer_zone_connections yes)
			)
		)
		(pad "20" smd rect
			(at -4.5 1.31 270)
			(size 0.3 1.5)
			(layers "B.Cu" "B.Mask" "B.Paste")
			(net 226 "unconnected-(J5-NC-Pad20)")
			(pinfunction "NC")
			(pintype "no_connect")
			(teardrops
				(best_length_ratio 0.2)
				(max_length 1)
				(best_width_ratio 0.9)
				(max_width 2)
				(curved_edges yes)
				(filter_ratio 0.9)
				(enabled yes)
				(allow_two_segments yes)
				(prefer_zone_connections yes)
			)
		)
		(pad "21" smd rect
			(at -4.25 3.95 270)
			(size 0.3 1.5)
			(layers "B.Cu" "B.Mask" "B.Paste")
			(net 1 "GND")
			(pinfunction "GND")
			(pintype "passive")
			(teardrops
				(best_length_ratio 0.2)
				(max_length 1)
				(best_width_ratio 0.9)
				(max_width 2)
				(curved_edges yes)
				(filter_ratio 0.9)
				(enabled yes)
				(allow_two_segments yes)
				(prefer_zone_connections yes)
			)
		)
		(pad "22" smd rect
			(at -4 1.31 270)
			(size 0.3 1.5)
			(layers "B.Cu" "B.Mask" "B.Paste")
			(net 230 "unconnected-(J5-NC-Pad22)")
			(pinfunction "NC")
			(pintype "no_connect")
			(teardrops
				(best_length_ratio 0.2)
				(max_length 1)
				(best_width_ratio 0.9)
				(max_width 2)
				(curved_edges yes)
				(filter_ratio 0.9)
				(enabled yes)
				(allow_two_segments yes)
				(prefer_zone_connections yes)
			)
		)
		(pad "23" smd rect
			(at -3.75 3.95 270)
			(size 0.3 1.5)
			(layers "B.Cu" "B.Mask" "B.Paste")
			(net 249 "/Com Express 7 Interfaces/PCIe_{B2Bx4}.TX2+")
			(pinfunction "PET2_N")
			(pintype "input")
			(teardrops
				(best_length_ratio 0.2)
				(max_length 1)
				(best_width_ratio 0.9)
				(max_width 2)
				(curved_edges yes)
				(filter_ratio 0.9)
				(enabled yes)
				(allow_two_segments yes)
				(prefer_zone_connections yes)
			)
		)
		(pad "24" smd rect
			(at -3.5 1.31 270)
			(size 0.3 1.5)
			(layers "B.Cu" "B.Mask" "B.Paste")
			(net 232 "unconnected-(J5-NC-Pad24)")
			(pinfunction "NC")
			(pintype "no_connect")
			(teardrops
				(best_length_ratio 0.2)
				(max_length 1)
				(best_width_ratio 0.9)
				(max_width 2)
				(curved_edges yes)
				(filter_ratio 0.9)
				(enabled yes)
				(allow_two_segments yes)
				(prefer_zone_connections yes)
			)
		)
		(pad "25" smd rect
			(at -3.25 3.95 270)
			(size 0.3 1.5)
			(layers "B.Cu" "B.Mask" "B.Paste")
			(net 247 "/Com Express 7 Interfaces/PCIe_{B2Bx4}.TX2-")
			(pinfunction "PET2_P")
			(pintype "input")
			(teardrops
				(best_length_ratio 0.2)
				(max_length 1)
				(best_width_ratio 0.9)
				(max_width 2)
				(curved_edges yes)
				(filter_ratio 0.9)
				(enabled yes)
				(allow_two_segments yes)
				(prefer_zone_connections yes)
			)
		)
		(pad "26" smd rect
			(at -3 1.31 270)
			(size 0.3 1.5)
			(layers "B.Cu" "B.Mask" "B.Paste")
			(net 233 "unconnected-(J5-NC-Pad26)")
			(pinfunction "NC")
			(pintype "no_connect")
			(teardrops
				(best_length_ratio 0.2)
				(max_length 1)
				(best_width_ratio 0.9)
				(max_width 2)
				(curved_edges yes)
				(filter_ratio 0.9)
				(enabled yes)
				(allow_two_segments yes)
				(prefer_zone_connections yes)
			)
		)
		(pad "27" smd rect
			(at -2.75 3.95 270)
			(size 0.3 1.5)
			(layers "B.Cu" "B.Mask" "B.Paste")
			(net 1 "GND")
			(pinfunction "GND")
			(pintype "passive")
			(teardrops
				(best_length_ratio 0.2)
				(max_length 1)
				(best_width_ratio 0.9)
				(max_width 2)
				(curved_edges yes)
				(filter_ratio 0.9)
				(enabled yes)
				(allow_two_segments yes)
				(prefer_zone_connections yes)
			)
		)
		(pad "28" smd rect
			(at -2.5 1.31 270)
			(size 0.3 1.5)
			(layers "B.Cu" "B.Mask" "B.Paste")
			(net 234 "unconnected-(J5-NC-Pad28)")
			(pinfunction "NC")
			(pintype "no_connect")
			(teardrops
				(best_length_ratio 0.2)
				(max_length 1)
				(best_width_ratio 0.9)
				(max_width 2)
				(curved_edges yes)
				(filter_ratio 0.9)
				(enabled yes)
				(allow_two_segments yes)
				(prefer_zone_connections yes)
			)
		)
		(pad "29" smd rect
			(at -2.25 3.95 270)
			(size 0.3 1.5)
			(layers "B.Cu" "B.Mask" "B.Paste")
			(net 254 "/Com Express 7 Interfaces/PCIe_{B2Bx4}.RX1+")
			(pinfunction "PER1_N")
			(pintype "output")
			(teardrops
				(best_length_ratio 0.2)
				(max_length 1)
				(best_width_ratio 0.9)
				(max_width 2)
				(curved_edges yes)
				(filter_ratio 0.9)
				(enabled yes)
				(allow_two_segments yes)
				(prefer_zone_connections yes)
			)
		)
		(pad "30" smd rect
			(at -2 1.31 270)
			(size 0.3 1.5)
			(layers "B.Cu" "B.Mask" "B.Paste")
			(net 235 "unconnected-(J5-NC-Pad30)")
			(pinfunction "NC")
			(pintype "no_connect")
			(teardrops
				(best_length_ratio 0.2)
				(max_length 1)
				(best_width_ratio 0.9)
				(max_width 2)
				(curved_edges yes)
				(filter_ratio 0.9)
				(enabled yes)
				(allow_two_segments yes)
				(prefer_zone_connections yes)
			)
		)
		(pad "31" smd rect
			(at -1.75 3.95 270)
			(size 0.3 1.5)
			(layers "B.Cu" "B.Mask" "B.Paste")
			(net 252 "/Com Express 7 Interfaces/PCIe_{B2Bx4}.RX1-")
			(pinfunction "PER1_P")
			(pintype "output")
			(teardrops
				(best_length_ratio 0.2)
				(max_length 1)
				(best_width_ratio 0.9)
				(max_width 2)
				(curved_edges yes)
				(filter_ratio 0.9)
				(enabled yes)
				(allow_two_segments yes)
				(prefer_zone_connections yes)
			)
		)
		(pad "32" smd rect
			(at -1.5 1.31 270)
			(size 0.3 1.5)
			(layers "B.Cu" "B.Mask" "B.Paste")
			(net 236 "unconnected-(J5-NC-Pad32)")
			(pinfunction "NC")
			(pintype "no_connect")
			(teardrops
				(best_length_ratio 0.2)
				(max_length 1)
				(best_width_ratio 0.9)
				(max_width 2)
				(curved_edges yes)
				(filter_ratio 0.9)
				(enabled yes)
				(allow_two_segments yes)
				(prefer_zone_connections yes)
			)
		)
		(pad "33" smd rect
			(at -1.25 3.95 270)
			(size 0.3 1.5)
			(layers "B.Cu" "B.Mask" "B.Paste")
			(net 1 "GND")
			(pinfunction "GND")
			(pintype "passive")
			(teardrops
				(best_length_ratio 0.2)
				(max_length 1)
				(best_width_ratio 0.9)
				(max_width 2)
				(curved_edges yes)
				(filter_ratio 0.9)
				(enabled yes)
				(allow_two_segments yes)
				(prefer_zone_connections yes)
			)
		)
		(pad "34" smd rect
			(at -1 1.31 270)
			(size 0.3 1.5)
			(layers "B.Cu" "B.Mask" "B.Paste")
			(net 914 "unconnected-(J5-NC-Pad34)")
			(pinfunction "NC")
			(pintype "no_connect")
			(teardrops
				(best_length_ratio 0.2)
				(max_length 1)
				(best_width_ratio 0.9)
				(max_width 2)
				(curved_edges yes)
				(filter_ratio 0.9)
				(enabled yes)
				(allow_two_segments yes)
				(prefer_zone_connections yes)
			)
		)
		(pad "35" smd rect
			(at -0.75 3.95 270)
			(size 0.3 1.5)
			(layers "B.Cu" "B.Mask" "B.Paste")
			(net 259 "/Com Express 7 Interfaces/PCIe_{B2Bx4}.TX1+")
			(pinfunction "PET1_N")
			(pintype "input")
			(teardrops
				(best_length_ratio 0.2)
				(max_length 1)
				(best_width_ratio 0.9)
				(max_width 2)
				(curved_edges yes)
				(filter_ratio 0.9)
				(enabled yes)
				(allow_two_segments yes)
				(prefer_zone_connections yes)
			)
		)
		(pad "36" smd rect
			(at -0.5 1.31 270)
			(size 0.3 1.5)
			(layers "B.Cu" "B.Mask" "B.Paste")
			(net 915 "unconnected-(J5-NC-Pad36)")
			(pinfunction "NC")
			(pintype "no_connect")
			(teardrops
				(best_length_ratio 0.2)
				(max_length 1)
				(best_width_ratio 0.9)
				(max_width 2)
				(curved_edges yes)
				(filter_ratio 0.9)
				(enabled yes)
				(allow_two_segments yes)
				(prefer_zone_connections yes)
			)
		)
		(pad "37" smd rect
			(at -0.25 3.95 270)
			(size 0.3 1.5)
			(layers "B.Cu" "B.Mask" "B.Paste")
			(net 257 "/Com Express 7 Interfaces/PCIe_{B2Bx4}.TX1-")
			(pinfunction "PET1_P")
			(pintype "input")
			(teardrops
				(best_length_ratio 0.2)
				(max_length 1)
				(best_width_ratio 0.9)
				(max_width 2)
				(curved_edges yes)
				(filter_ratio 0.9)
				(enabled yes)
				(allow_two_segments yes)
				(prefer_zone_connections yes)
			)
		)
		(pad "38" smd rect
			(at 0 1.31 270)
			(size 0.3 1.5)
			(layers "B.Cu" "B.Mask" "B.Paste")
			(net 916 "unconnected-(J5-NC-Pad38)")
			(pinfunction "NC")
			(pintype "no_connect")
			(teardrops
				(best_length_ratio 0.2)
				(max_length 1)
				(best_width_ratio 0.9)
				(max_width 2)
				(curved_edges yes)
				(filter_ratio 0.9)
				(enabled yes)
				(allow_two_segments yes)
				(prefer_zone_connections yes)
			)
		)
		(pad "39" smd rect
			(at 0.25 3.95 270)
			(size 0.3 1.5)
			(layers "B.Cu" "B.Mask" "B.Paste")
			(net 1 "GND")
			(pinfunction "GND")
			(pintype "passive")
			(teardrops
				(best_length_ratio 0.2)
				(max_length 1)
				(best_width_ratio 0.9)
				(max_width 2)
				(curved_edges yes)
				(filter_ratio 0.9)
				(enabled yes)
				(allow_two_segments yes)
				(prefer_zone_connections yes)
			)
		)
		(pad "40" smd rect
			(at 0.5 1.31 270)
			(size 0.3 1.5)
			(layers "B.Cu" "B.Mask" "B.Paste")
			(net 917 "unconnected-(J5-SMB_CLK-Pad40)")
			(pinfunction "SMB_CLK")
			(pintype "input+no_connect")
			(teardrops
				(best_length_ratio 0.2)
				(max_length 1)
				(best_width_ratio 0.9)
				(max_width 2)
				(curved_edges yes)
				(filter_ratio 0.9)
				(enabled yes)
				(allow_two_segments yes)
				(prefer_zone_connections yes)
			)
		)
	)
)
